G04*
G04 #@! TF.GenerationSoftware,Altium Limited,Altium Designer,22.4.2 (48)*
G04*
G04 Layer_Color=8388736*
%FSLAX25Y25*%
%MOIN*%
G70*
G04*
G04 #@! TF.SameCoordinates,B69760C6-9901-4916-8BAC-4CFDAA04743E*
G04*
G04*
G04 #@! TF.FilePolarity,Negative*
G04*
G01*
G75*
%ADD19R,0.01860X0.02288*%
%ADD20R,0.02288X0.01860*%
%ADD21R,0.01968X0.02362*%
%ADD22R,0.02362X0.01968*%
%ADD23R,0.19685X0.03937*%
%ADD24C,0.03937*%
%ADD31R,0.02423X0.02254*%
%ADD34R,0.02559X0.03347*%
%ADD35R,0.02254X0.02423*%
%ADD36R,0.01788X0.01428*%
%ADD41R,0.03543X0.03543*%
%ADD42C,0.04331*%
G04:AMPARAMS|DCode=43|XSize=19.75mil|YSize=37.47mil|CornerRadius=3.97mil|HoleSize=0mil|Usage=FLASHONLY|Rotation=180.000|XOffset=0mil|YOffset=0mil|HoleType=Round|Shape=RoundedRectangle|*
%AMROUNDEDRECTD43*
21,1,0.01975,0.02953,0,0,180.0*
21,1,0.01181,0.03747,0,0,180.0*
1,1,0.00794,-0.00591,0.01476*
1,1,0.00794,0.00591,0.01476*
1,1,0.00794,0.00591,-0.01476*
1,1,0.00794,-0.00591,-0.01476*
%
%ADD43ROUNDEDRECTD43*%
%ADD44R,0.03550X0.06306*%
%ADD45R,0.06306X0.03550*%
%ADD46R,0.04731X0.04731*%
%ADD47R,0.02835X0.02756*%
G04:AMPARAMS|DCode=48|XSize=15.81mil|YSize=35.5mil|CornerRadius=3.95mil|HoleSize=0mil|Usage=FLASHONLY|Rotation=90.000|XOffset=0mil|YOffset=0mil|HoleType=Round|Shape=RoundedRectangle|*
%AMROUNDEDRECTD48*
21,1,0.01581,0.02760,0,0,90.0*
21,1,0.00791,0.03550,0,0,90.0*
1,1,0.00790,0.01380,0.00396*
1,1,0.00790,0.01380,-0.00396*
1,1,0.00790,-0.01380,-0.00396*
1,1,0.00790,-0.01380,0.00396*
%
%ADD48ROUNDEDRECTD48*%
%ADD49R,0.03543X0.03937*%
%ADD50R,0.04331X0.03937*%
%ADD51R,0.02756X0.02835*%
%ADD52R,0.12014X0.04416*%
G04:AMPARAMS|DCode=53|XSize=15.81mil|YSize=35.5mil|CornerRadius=3.95mil|HoleSize=0mil|Usage=FLASHONLY|Rotation=0.000|XOffset=0mil|YOffset=0mil|HoleType=Round|Shape=RoundedRectangle|*
%AMROUNDEDRECTD53*
21,1,0.01581,0.02760,0,0,0.0*
21,1,0.00791,0.03550,0,0,0.0*
1,1,0.00790,0.00396,-0.01380*
1,1,0.00790,-0.00396,-0.01380*
1,1,0.00790,-0.00396,0.01380*
1,1,0.00790,0.00396,0.01380*
%
%ADD53ROUNDEDRECTD53*%
G36*
X26933Y106224D02*
X26846Y105379D01*
X26367Y103749D01*
X25599Y102234D01*
X24567Y100884D01*
X23305Y99746D01*
X21858Y98857D01*
X20272Y98247D01*
X18601Y97937D01*
X17752Y97937D01*
X1185D01*
Y120807D01*
X1185Y121102D01*
X1301Y121681D01*
X1528Y122226D01*
X1856Y122717D01*
X2274Y123134D01*
X2765Y123462D01*
X3311Y123688D01*
X3890Y123803D01*
X4185Y123803D01*
X4185Y123803D01*
X26933D01*
X26933Y106224D01*
D02*
G37*
G36*
X260268Y123803D02*
X260268Y123803D01*
X260268D01*
X260728Y123769D01*
X261095Y123701D01*
X261616Y123500D01*
X262090Y123207D01*
X262504Y122831D01*
X262841Y122387D01*
X263091Y121888D01*
X263245Y121352D01*
X263272Y121074D01*
X263272Y97937D01*
X241059Y97937D01*
X240347D01*
X238948Y98207D01*
X237626Y98738D01*
X236429Y99510D01*
X235400Y100495D01*
X234577Y101657D01*
X233988Y102954D01*
X233657Y104340D01*
X233626Y105051D01*
X233626Y123803D01*
X260268D01*
X260268Y123803D01*
D02*
G37*
G36*
X36835Y92250D02*
X36873Y92238D01*
X36908Y92220D01*
X36938Y92194D01*
X36963Y92164D01*
X36982Y92129D01*
X36993Y92092D01*
X36997Y92052D01*
Y82752D01*
X36993Y82713D01*
X36982Y82675D01*
X36963Y82641D01*
X36938Y82610D01*
X36908Y82585D01*
X36873Y82567D01*
X36835Y82555D01*
X36796Y82551D01*
X29258D01*
X29248Y82552D01*
X29237Y82553D01*
X29228Y82554D01*
X29219Y82555D01*
X29209Y82558D01*
X29198Y82561D01*
X29190Y82564D01*
X29181Y82567D01*
X29172Y82572D01*
X29162Y82576D01*
X29155Y82581D01*
X29147Y82585D01*
X29138Y82592D01*
X29129Y82598D01*
X29123Y82605D01*
X29116Y82610D01*
X29109Y82619D01*
X29102Y82626D01*
X28717Y83104D01*
X27846Y83960D01*
X26856Y84669D01*
X25768Y85216D01*
X24608Y85589D01*
X23405Y85777D01*
X22187D01*
X20984Y85589D01*
X19824Y85216D01*
X18736Y84669D01*
X17746Y83960D01*
X16875Y83104D01*
X16490Y82626D01*
X16483Y82619D01*
X16476Y82610D01*
X16469Y82605D01*
X16463Y82598D01*
X16454Y82592D01*
X16445Y82585D01*
X16437Y82581D01*
X16430Y82576D01*
X16420Y82572D01*
X16410Y82567D01*
X16402Y82564D01*
X16394Y82561D01*
X16383Y82558D01*
X16373Y82555D01*
X16364Y82554D01*
X16355Y82553D01*
X16344Y82552D01*
X16334Y82551D01*
X8796D01*
X8757Y82555D01*
X8719Y82567D01*
X8684Y82585D01*
X8654Y82610D01*
X8629Y82641D01*
X8610Y82675D01*
X8599Y82713D01*
X8595Y82752D01*
Y92052D01*
X8599Y92092D01*
X8610Y92129D01*
X8629Y92164D01*
X8654Y92194D01*
X8684Y92220D01*
X8719Y92238D01*
X8757Y92250D01*
X8796Y92253D01*
X36796D01*
X36835Y92250D01*
D02*
G37*
G36*
X23170Y81550D02*
X23827Y81419D01*
X23865Y81407D01*
X23865Y81407D01*
X24483Y81151D01*
X24518Y81133D01*
X25075Y80761D01*
X25105Y80735D01*
X25106Y80735D01*
X25579Y80262D01*
X25604Y80231D01*
X25976Y79675D01*
X25976Y79675D01*
X25995Y79640D01*
X26251Y79021D01*
X26262Y78983D01*
X26393Y78326D01*
X26397Y78287D01*
Y77952D01*
Y77618D01*
X26393Y77578D01*
X26262Y76921D01*
X26251Y76884D01*
X26251Y76884D01*
X25995Y76265D01*
X25976Y76230D01*
X25604Y75673D01*
X25579Y75643D01*
X25579Y75643D01*
X25105Y75169D01*
X25075Y75144D01*
X24518Y74772D01*
X24518Y74772D01*
X24483Y74754D01*
X23865Y74497D01*
X23827Y74486D01*
X23170Y74355D01*
X23131Y74351D01*
X22461D01*
X22422Y74355D01*
X21765Y74486D01*
X21727Y74497D01*
X21727Y74497D01*
X21109Y74754D01*
X21074Y74772D01*
X20517Y75144D01*
X20486Y75169D01*
X20486Y75169D01*
X20013Y75643D01*
X19988Y75673D01*
X19616Y76230D01*
X19616Y76230D01*
X19597Y76265D01*
X19341Y76884D01*
X19330Y76921D01*
X19199Y77578D01*
X19195Y77618D01*
Y77952D01*
Y78287D01*
X19199Y78326D01*
X19330Y78983D01*
X19341Y79021D01*
X19341Y79021D01*
X19597Y79640D01*
X19616Y79675D01*
X19988Y80231D01*
X20013Y80262D01*
X20013Y80262D01*
X20486Y80735D01*
X20517Y80761D01*
X21074Y81133D01*
X21074Y81133D01*
X21109Y81151D01*
X21727Y81407D01*
X21765Y81419D01*
X22422Y81550D01*
X22461Y81553D01*
X23131D01*
X23170Y81550D01*
D02*
G37*
G36*
X36835Y73349D02*
X36873Y73338D01*
X36908Y73320D01*
X36938Y73295D01*
X36963Y73264D01*
X36982Y73229D01*
X36993Y73192D01*
X36997Y73152D01*
Y63852D01*
X36993Y63813D01*
X36982Y63775D01*
X36963Y63741D01*
X36938Y63710D01*
X36908Y63685D01*
X36873Y63667D01*
X36835Y63655D01*
X36796Y63651D01*
X8796D01*
X8757Y63655D01*
X8719Y63667D01*
X8684Y63685D01*
X8654Y63710D01*
X8629Y63741D01*
X8610Y63775D01*
X8599Y63813D01*
X8595Y63852D01*
Y73152D01*
X8599Y73192D01*
X8610Y73229D01*
X8629Y73264D01*
X8654Y73295D01*
X8684Y73320D01*
X8719Y73338D01*
X8757Y73349D01*
X8796Y73353D01*
X16334D01*
X16344Y73352D01*
X16355Y73352D01*
X16364Y73350D01*
X16373Y73349D01*
X16383Y73346D01*
X16394Y73344D01*
X16402Y73341D01*
X16410Y73338D01*
X16420Y73333D01*
X16430Y73329D01*
X16437Y73324D01*
X16445Y73320D01*
X16454Y73312D01*
X16463Y73307D01*
X16469Y73300D01*
X16476Y73295D01*
X16483Y73286D01*
X16490Y73278D01*
X16875Y72801D01*
X17746Y71944D01*
X18736Y71236D01*
X19824Y70688D01*
X20984Y70316D01*
X22187Y70128D01*
X23405D01*
X24608Y70316D01*
X25768Y70688D01*
X26855Y71235D01*
X27846Y71944D01*
X28717Y72801D01*
X29102Y73278D01*
X29109Y73286D01*
X29116Y73295D01*
X29123Y73300D01*
X29129Y73307D01*
X29138Y73313D01*
X29147Y73320D01*
X29155Y73324D01*
X29162Y73329D01*
X29172Y73333D01*
X29181Y73338D01*
X29190Y73341D01*
X29198Y73344D01*
X29209Y73346D01*
X29219Y73349D01*
X29228Y73350D01*
X29237Y73352D01*
X29248Y73352D01*
X29258Y73353D01*
X36796Y73353D01*
X36835Y73349D01*
D02*
G37*
G36*
X23143Y26843D02*
X24075Y26473D01*
X24920Y25934D01*
X25649Y25246D01*
X26236Y24433D01*
X26659Y23524D01*
X26904Y22552D01*
X26933Y22051D01*
X26933Y1165D01*
X4197D01*
X3909Y1165D01*
X3344Y1274D01*
X2810Y1488D01*
X2325Y1799D01*
X1909Y2196D01*
X1575Y2664D01*
X1335Y3188D01*
X1199Y3747D01*
X1185Y4034D01*
Y27031D01*
X21657D01*
X21657Y27031D01*
X21657Y27031D01*
X22159Y27031D01*
X23143Y26843D01*
D02*
G37*
G36*
X263353Y3912D02*
X263330Y3630D01*
X263180Y3083D01*
X262931Y2574D01*
X262592Y2119D01*
X262175Y1735D01*
X261695Y1435D01*
X261166Y1229D01*
X260810Y1162D01*
X260326Y1124D01*
X233708Y1124D01*
X233708Y20395D01*
X233742Y21057D01*
X234060Y22343D01*
X234614Y23546D01*
X235386Y24623D01*
X236347Y25535D01*
X237463Y26249D01*
X238693Y26740D01*
X239994Y26990D01*
X240656D01*
X240656Y26990D01*
X263353D01*
X263353Y3912D01*
D02*
G37*
%LPC*%
G36*
X11825Y120886D02*
X10623D01*
X10525Y120866D01*
X10424D01*
X9245Y120632D01*
X9153Y120593D01*
X9054Y120574D01*
X7944Y120114D01*
X7860Y120058D01*
X7767Y120019D01*
X6768Y119351D01*
X6697Y119281D01*
X6613Y119225D01*
X5763Y118375D01*
X5708Y118291D01*
X5637Y118220D01*
X4969Y117221D01*
X4930Y117128D01*
X4875Y117044D01*
X4415Y115934D01*
X4395Y115835D01*
X4357Y115743D01*
X4122Y114564D01*
Y114463D01*
X4103Y114365D01*
Y113764D01*
Y113163D01*
X4122Y113064D01*
Y112964D01*
X4357Y111785D01*
X4395Y111692D01*
X4415Y111594D01*
X4875Y110483D01*
X4930Y110399D01*
X4969Y110307D01*
X5637Y109307D01*
X5708Y109236D01*
X5763Y109153D01*
X6613Y108303D01*
X6697Y108247D01*
X6768Y108176D01*
X7767Y107508D01*
X7860Y107470D01*
X7944Y107414D01*
X9054Y106954D01*
X9153Y106934D01*
X9245Y106896D01*
X10424Y106661D01*
X10525D01*
X10623Y106642D01*
X11825D01*
X11924Y106661D01*
X12024D01*
X13203Y106896D01*
X13296Y106934D01*
X13395Y106954D01*
X14505Y107414D01*
X14589Y107470D01*
X14681Y107508D01*
X15681Y108176D01*
X15752Y108247D01*
X15835Y108303D01*
X16685Y109153D01*
X16741Y109236D01*
X16812Y109307D01*
X17480Y110307D01*
X17518Y110399D01*
X17574Y110483D01*
X18034Y111594D01*
X18054Y111692D01*
X18092Y111785D01*
X18327Y112964D01*
Y113064D01*
X18346Y113163D01*
Y113764D01*
Y114365D01*
X18327Y114463D01*
Y114564D01*
X18092Y115743D01*
X18054Y115835D01*
X18034Y115934D01*
X17574Y117044D01*
X17518Y117128D01*
X17480Y117221D01*
X16812Y118220D01*
X16741Y118291D01*
X16685Y118375D01*
X15835Y119225D01*
X15752Y119281D01*
X15681Y119351D01*
X14681Y120019D01*
X14589Y120058D01*
X14505Y120114D01*
X13395Y120574D01*
X13296Y120593D01*
X13203Y120632D01*
X12024Y120866D01*
X11924D01*
X11825Y120886D01*
D02*
G37*
G36*
X250014D02*
X248812D01*
X248714Y120866D01*
X248613D01*
X247434Y120632D01*
X247342Y120593D01*
X247243Y120574D01*
X246133Y120114D01*
X246049Y120058D01*
X245956Y120019D01*
X244957Y119351D01*
X244886Y119281D01*
X244802Y119225D01*
X243952Y118375D01*
X243897Y118291D01*
X243826Y118220D01*
X243158Y117221D01*
X243119Y117128D01*
X243064Y117044D01*
X242604Y115934D01*
X242584Y115835D01*
X242546Y115743D01*
X242311Y114564D01*
Y114463D01*
X242291Y114365D01*
Y113163D01*
X242311Y113064D01*
Y112964D01*
X242546Y111785D01*
X242584Y111692D01*
X242604Y111594D01*
X243064Y110483D01*
X243119Y110399D01*
X243158Y110307D01*
X243826Y109307D01*
X243897Y109236D01*
X243952Y109153D01*
X244802Y108303D01*
X244886Y108247D01*
X244957Y108176D01*
X245956Y107508D01*
X246049Y107470D01*
X246133Y107414D01*
X247243Y106954D01*
X247342Y106934D01*
X247434Y106896D01*
X248613Y106661D01*
X248714D01*
X248812Y106642D01*
X250014D01*
X250113Y106661D01*
X250213D01*
X251392Y106896D01*
X251485Y106934D01*
X251584Y106954D01*
X252694Y107414D01*
X252778Y107470D01*
X252870Y107508D01*
X253870Y108176D01*
X253941Y108247D01*
X254024Y108303D01*
X254874Y109153D01*
X254930Y109236D01*
X255001Y109307D01*
X255669Y110307D01*
X255707Y110399D01*
X255763Y110483D01*
X256223Y111594D01*
X256243Y111692D01*
X256281Y111785D01*
X256516Y112964D01*
Y113064D01*
X256535Y113163D01*
Y114365D01*
X256516Y114463D01*
Y114564D01*
X256281Y115743D01*
X256243Y115835D01*
X256223Y115934D01*
X255763Y117044D01*
X255707Y117128D01*
X255669Y117221D01*
X255001Y118220D01*
X254930Y118291D01*
X254874Y118375D01*
X254024Y119225D01*
X253941Y119281D01*
X253870Y119351D01*
X252870Y120019D01*
X252778Y120058D01*
X252694Y120114D01*
X251584Y120574D01*
X251485Y120593D01*
X251392Y120632D01*
X250213Y120866D01*
X250113D01*
X250014Y120886D01*
D02*
G37*
G36*
X11825Y18523D02*
X10623D01*
X10525Y18504D01*
X10424D01*
X9245Y18269D01*
X9153Y18231D01*
X9054Y18211D01*
X7944Y17751D01*
X7860Y17696D01*
X7767Y17657D01*
X6768Y16989D01*
X6697Y16918D01*
X6613Y16862D01*
X5763Y16013D01*
X5708Y15929D01*
X5637Y15858D01*
X4969Y14859D01*
X4930Y14766D01*
X4875Y14682D01*
X4415Y13572D01*
X4395Y13473D01*
X4357Y13381D01*
X4122Y12201D01*
Y12101D01*
X4103Y12003D01*
Y10801D01*
X4122Y10702D01*
Y10602D01*
X4357Y9423D01*
X4395Y9330D01*
X4415Y9231D01*
X4875Y8121D01*
X4930Y8037D01*
X4969Y7945D01*
X5637Y6945D01*
X5708Y6874D01*
X5763Y6791D01*
X6613Y5941D01*
X6697Y5885D01*
X6768Y5814D01*
X7767Y5146D01*
X7860Y5108D01*
X7944Y5052D01*
X9054Y4592D01*
X9153Y4572D01*
X9245Y4534D01*
X10424Y4299D01*
X10525D01*
X10623Y4280D01*
X11825D01*
X11924Y4299D01*
X12024D01*
X13203Y4534D01*
X13296Y4572D01*
X13395Y4592D01*
X14505Y5052D01*
X14589Y5108D01*
X14681Y5146D01*
X15681Y5814D01*
X15752Y5885D01*
X15835Y5941D01*
X16685Y6791D01*
X16741Y6874D01*
X16812Y6945D01*
X17480Y7945D01*
X17518Y8037D01*
X17574Y8121D01*
X18034Y9231D01*
X18054Y9330D01*
X18092Y9423D01*
X18327Y10602D01*
Y10702D01*
X18346Y10801D01*
Y12003D01*
X18327Y12101D01*
Y12201D01*
X18092Y13381D01*
X18054Y13473D01*
X18034Y13572D01*
X17574Y14682D01*
X17518Y14766D01*
X17480Y14859D01*
X16812Y15858D01*
X16741Y15929D01*
X16685Y16013D01*
X15835Y16862D01*
X15752Y16918D01*
X15681Y16989D01*
X14681Y17657D01*
X14589Y17696D01*
X14505Y17751D01*
X13395Y18211D01*
X13296Y18231D01*
X13203Y18269D01*
X12024Y18504D01*
X11924D01*
X11825Y18523D01*
D02*
G37*
G36*
X250014D02*
X248812D01*
X248714Y18504D01*
X248613D01*
X247434Y18269D01*
X247342Y18231D01*
X247243Y18211D01*
X246133Y17751D01*
X246049Y17696D01*
X245956Y17657D01*
X244957Y16989D01*
X244886Y16918D01*
X244802Y16862D01*
X243952Y16013D01*
X243897Y15929D01*
X243826Y15858D01*
X243158Y14859D01*
X243119Y14766D01*
X243064Y14682D01*
X242604Y13572D01*
X242584Y13473D01*
X242546Y13381D01*
X242311Y12201D01*
Y12101D01*
X242291Y12003D01*
Y10801D01*
X242311Y10702D01*
Y10602D01*
X242546Y9423D01*
X242584Y9330D01*
X242604Y9231D01*
X243064Y8121D01*
X243119Y8037D01*
X243158Y7945D01*
X243826Y6945D01*
X243897Y6874D01*
X243952Y6791D01*
X244802Y5941D01*
X244886Y5885D01*
X244957Y5814D01*
X245956Y5146D01*
X246049Y5108D01*
X246133Y5052D01*
X247243Y4592D01*
X247342Y4572D01*
X247434Y4534D01*
X248613Y4299D01*
X248714D01*
X248812Y4280D01*
X250014D01*
X250113Y4299D01*
X250213D01*
X251392Y4534D01*
X251485Y4572D01*
X251584Y4592D01*
X252694Y5052D01*
X252778Y5108D01*
X252870Y5146D01*
X253870Y5814D01*
X253941Y5885D01*
X254024Y5941D01*
X254874Y6791D01*
X254930Y6874D01*
X255001Y6945D01*
X255669Y7945D01*
X255707Y8037D01*
X255763Y8121D01*
X256223Y9231D01*
X256243Y9330D01*
X256281Y9423D01*
X256516Y10602D01*
Y10702D01*
X256535Y10801D01*
Y12003D01*
X256516Y12101D01*
Y12201D01*
X256281Y13381D01*
X256243Y13473D01*
X256223Y13572D01*
X255763Y14682D01*
X255707Y14766D01*
X255669Y14859D01*
X255001Y15858D01*
X254930Y15929D01*
X254874Y16013D01*
X254024Y16862D01*
X253941Y16918D01*
X253870Y16989D01*
X252870Y17657D01*
X252778Y17696D01*
X252694Y17751D01*
X251584Y18211D01*
X251485Y18231D01*
X251392Y18269D01*
X250213Y18504D01*
X250113D01*
X250014Y18523D01*
D02*
G37*
%LPD*%
D19*
X208132Y14520D02*
D03*
Y11642D02*
D03*
X239900Y79220D02*
D03*
Y76341D02*
D03*
X192400Y14520D02*
D03*
Y11642D02*
D03*
X211600Y52939D02*
D03*
Y50061D02*
D03*
X219800D02*
D03*
Y52939D02*
D03*
D20*
X63439Y18180D02*
D03*
X60561D02*
D03*
X70439Y46000D02*
D03*
X67561D02*
D03*
D21*
X84969Y48200D02*
D03*
X81032D02*
D03*
X81132Y69300D02*
D03*
X85069D02*
D03*
X63468Y46000D02*
D03*
X59531D02*
D03*
D22*
X212400Y68568D02*
D03*
Y64631D02*
D03*
X220100Y68568D02*
D03*
Y64631D02*
D03*
X133500Y100531D02*
D03*
Y104469D02*
D03*
D23*
X22795Y66472D02*
D03*
X21795Y88953D02*
D03*
D24*
X22796Y77952D02*
D03*
D31*
X76163Y69089D02*
D03*
X72789D02*
D03*
X210490Y43400D02*
D03*
X213864D02*
D03*
X78187Y77600D02*
D03*
X74813D02*
D03*
X60687Y53500D02*
D03*
X57313D02*
D03*
D34*
X43000Y72039D02*
D03*
Y76961D02*
D03*
D35*
X51500Y73813D02*
D03*
Y77187D02*
D03*
D36*
X51198Y65000D02*
D03*
X48802D02*
D03*
D41*
X249100Y84548D02*
D03*
Y78052D02*
D03*
X200168Y19848D02*
D03*
Y13352D02*
D03*
X215900D02*
D03*
Y19848D02*
D03*
D42*
X146000Y101500D02*
D03*
X140500D02*
D03*
X116500D02*
D03*
X111000D02*
D03*
X105500D02*
D03*
X174500Y15000D02*
D03*
X169000D02*
D03*
X163500D02*
D03*
D43*
X58441Y68929D02*
D03*
X63559D02*
D03*
Y60071D02*
D03*
X61000D02*
D03*
X58441D02*
D03*
D44*
X151154Y93039D02*
D03*
X146823D02*
D03*
X142492D02*
D03*
X138161D02*
D03*
X133831D02*
D03*
X129500D02*
D03*
X125169D02*
D03*
X112177D02*
D03*
X107846D02*
D03*
X103516D02*
D03*
X116508D02*
D03*
X120839D02*
D03*
X99185D02*
D03*
Y14693D02*
D03*
X103516D02*
D03*
X107846D02*
D03*
X112177D02*
D03*
X116508D02*
D03*
X120839D02*
D03*
X125169D02*
D03*
X129500D02*
D03*
X133831D02*
D03*
X138161D02*
D03*
X142492D02*
D03*
X146823D02*
D03*
X151154D02*
D03*
D45*
X95839Y82016D02*
D03*
Y77685D02*
D03*
Y73354D02*
D03*
Y69024D02*
D03*
Y64693D02*
D03*
Y60362D02*
D03*
Y56032D02*
D03*
Y51701D02*
D03*
Y47370D02*
D03*
Y43039D02*
D03*
Y38709D02*
D03*
Y34378D02*
D03*
Y30047D02*
D03*
Y25717D02*
D03*
X154500D02*
D03*
Y30047D02*
D03*
Y34378D02*
D03*
Y38709D02*
D03*
Y43039D02*
D03*
Y47370D02*
D03*
Y51701D02*
D03*
Y56032D02*
D03*
Y60362D02*
D03*
Y64693D02*
D03*
Y69024D02*
D03*
Y73354D02*
D03*
Y77685D02*
D03*
Y82016D02*
D03*
D46*
X104500Y24929D02*
D03*
Y33197D02*
D03*
Y41465D02*
D03*
Y49732D02*
D03*
Y58000D02*
D03*
Y66268D02*
D03*
Y74535D02*
D03*
X104500Y82803D02*
D03*
X112768Y24929D02*
D03*
Y33197D02*
D03*
Y41465D02*
D03*
Y49732D02*
D03*
Y58000D02*
D03*
Y66268D02*
D03*
Y74535D02*
D03*
X112768Y82803D02*
D03*
X121035Y24929D02*
D03*
Y33197D02*
D03*
Y41465D02*
D03*
Y49732D02*
D03*
Y58000D02*
D03*
Y66268D02*
D03*
Y74535D02*
D03*
X121035Y82803D02*
D03*
X129303Y24929D02*
D03*
Y33197D02*
D03*
Y41465D02*
D03*
Y49732D02*
D03*
Y58000D02*
D03*
Y66268D02*
D03*
Y74535D02*
D03*
X129303Y82803D02*
D03*
X137571Y24929D02*
D03*
Y33197D02*
D03*
Y41465D02*
D03*
Y49732D02*
D03*
Y58000D02*
D03*
Y66268D02*
D03*
Y74535D02*
D03*
X137571Y82803D02*
D03*
X145838Y24929D02*
D03*
Y33197D02*
D03*
Y41465D02*
D03*
Y49732D02*
D03*
Y58000D02*
D03*
Y66268D02*
D03*
Y74535D02*
D03*
X145838Y82803D02*
D03*
D47*
X127500Y104311D02*
D03*
Y100689D02*
D03*
D48*
X84299Y55347D02*
D03*
Y57316D02*
D03*
Y59284D02*
D03*
Y61253D02*
D03*
X71701Y55347D02*
D03*
Y57316D02*
D03*
Y59284D02*
D03*
Y61253D02*
D03*
D49*
X55760Y26563D02*
D03*
X63240D02*
D03*
X59500Y34437D02*
D03*
D50*
X51500Y45850D02*
D03*
Y52150D02*
D03*
D51*
X161689Y46000D02*
D03*
X165311D02*
D03*
Y51500D02*
D03*
X161689D02*
D03*
X165311Y60000D02*
D03*
X161689D02*
D03*
Y65500D02*
D03*
X165311D02*
D03*
D52*
X249390Y32598D02*
D03*
Y40472D02*
D03*
Y48346D02*
D03*
Y56221D02*
D03*
X231476Y32598D02*
D03*
Y40472D02*
D03*
Y48346D02*
D03*
Y56221D02*
D03*
D53*
X197647Y43401D02*
D03*
X199616D02*
D03*
X201584D02*
D03*
X203553D02*
D03*
X197647Y55999D02*
D03*
X199616D02*
D03*
X201584D02*
D03*
X203553D02*
D03*
M02*
